FILE_TYPE = CONNECTIVITY;
{Allegro Design Entry HDL 16.6-p007 (v16-6-112F) 10/10/2012}
"PAGE_NUMBER" = 169;
0"NC";
1"GND\g";
2"GND\g";
3"P5V_STBY\g";
4"P1V05_PCH_STBY\g"CDS_PHYS_NET_NAME"<<OCC_ONLY>>";
5"P3V3_STBY\g";
6"P12V_STBY\g";
7"GND\g";
8"P5V\g";
9"GND\g";
10"P3V3\g";
11"PVNN_PCH_STBY\g"CDS_PHYS_NET_NAME"<<OCC_ONLY>>";
12"GND\g";
13"GND\g";
14"P3V3_STBY\g";
15"P3V3_STBY\g";
16"GND\g";
17"GND\g";
18"GND\g";
19"GND\g";
20"A_P3V_BAT_SCALED"VOLTAGE"+1V"CDS_PHYS_NET_NAME"<<OCC_ONLY>>";
21"A_P5V_SCALED"VOLTAGE"+2V";
22"A_P5V_STBY_SCALED"VOLTAGE"+2V"CDS_PHYS_NET_NAME"<<OCC_ONLY>>";
23"A_P3V3_STBY_SCALED"VOLTAGE"+1.8V"CDS_PHYS_NET_NAME"<<OCC_ONLY>>";
24"A_P1V05_STBY_PCH_SENSOR"VOLTAGE"+1.2V"CDS_PHYS_NET_NAME"<<OCC_ONLY>>";
25"A_P12V_STBY_SCALED"VOLTAGE"+2V"CDS_PHYS_NET_NAME"<<OCC_ONLY>>";
26"A_P3V3_SCALED"VOLTAGE"+2V";
27"A_PVNN_STBY_PCH_SENSOR"VOLTAGE"+1.2V"CDS_PHYS_NET_NAME"<<OCC_ONLY>>";
28"FM_BATTERY_SENSE_EN";
29"P3V_BAT_SOURCE_R"VOLTAGE"+3V";
30"FM_BATTERY_SENSE_EN_N";
31"A_P3V_BAT_R";
%"RES"
"2","(400,2725)","0","mstr_discrete","I106";
;
CDS_SEC"1"
WATTAGE"1/16W"
MATERIAL"CHIP"
PACK_TYPE"0402"
TOLERANCE"1%"
VALUE"100.0K"
PART_NUMBER"G21796-010"
LOCATION"R9G26"
ROOM"BMC_VOLT_MONITOR"
CDS_LOCATION"R9G26"
SEC"1"
BOM_COST"SM_HM"
SEC_TYPE"0402"
CDS_LIB"mstr_discrete";
"A"
$PN"1"20;
"B"
$PN"2"1;
%"GND"
"1","(400,2500)","0","mstr_symbols","I107";
;
HDL_POWER"GND"
BODY_TYPE"PLUMBING"
SIZE"1B"
CDS_LIB"mstr_symbols"
VOLTAGE"0";
"A\NAC"1;
%"CAP"
"1","(800,2700)","0","mstr_discrete","I108";
;
CDS_SEC"1"
PART_NUMBER"A36094-025"
PACK_TYPE"0402LF"
TOLERANCE"5%"
MATERIAL"COG"
VOLTAGE"50V"
VALUE"10.0PF"
LOCATION"C9G22"
ROOM"BMC_VOLT_MONITOR"
CDS_LOCATION"C9G22"
SEC"1"
BOM_COST"SM_HM"
SEC_TYPE"0402LF"
CDS_LIB"mstr_discrete";
"A"
$PN"1"20;
"B"
$PN"2"2;
%"GND"
"1","(800,2500)","0","mstr_symbols","I109";
;
HDL_POWER"GND"
BODY_TYPE"PLUMBING"
SIZE"1B"
CDS_LIB"mstr_symbols"
VOLTAGE"0";
"A\NAC"2;
%"RES"
"2","(-2850,1750)","0","mstr_discrete","I115";
;
CDS_SEC"1"
WATTAGE"1/16W"
VALUE"5.11K"
MATERIAL"CHIP"
TOLERANCE"1%"
LOCATION"R1U47"
PACK_TYPE"0402"
PART_NUMBER"G21796-140"
ROOM"BMC_VOLT_MONITOR"
CDS_LOCATION"R1U47"
SEC"1"
BOM_COST"SM_HM"
CDS_LIB"mstr_discrete"
SEC_TYPE"0402";
"A"
$PN"1"3;
"B"
$PN"2"22;
%"P5V_STBY"
"1","(-2850,1975)","0","mstr_symbols","I119";
;
HDL_POWER"P5V_STBY"
BODY_TYPE"PLUMBING"
CDS_LIB"mstr_symbols"
SIZE"1B"
VOLTAGE"5.0V";
"G\NAC"3;
%"P1V05_PCH_STBY"
"1","(-4825,3775)","0","mstr_symbols","I121";
;
HDL_POWER"P1V05_PCH_STBY"
BODY_TYPE"PLUMBING"
CDS_LIB"mstr_symbols"
VOLTAGE"1.05V";
"G\NAC"4;
%"RES"
"2","(200,4025)","0","mstr_discrete","I126";
;
CDS_SEC"1"
VALUE"200.0K"
WATTAGE"1/16W"
MATERIAL"CHIP"
PACK_TYPE"0402"
TOLERANCE"1%"
LOCATION"R1U50"
PART_NUMBER"G21796-080"
ROOM"BMC_VOLT_MONITOR"
CDS_LOCATION"R1U50"
SEC"1"
BOM_COST"SM_HM"
SEC_TYPE"0402"
CDS_LIB"mstr_discrete";
"A"
$PN"1"31;
"B"
$PN"2"29;
%"P3V3_STBY"
"1","(-4825,2000)","0","mstr_symbols","I131";
;
HDL_POWER"P3V3_STBY"
BODY_TYPE"PLUMBING"
CDS_LIB"mstr_symbols"
SIZE"1B"
VOLTAGE"3.3V";
"G\NAC"5;
%"P12V_STBY"
"1","(-1125,2025)","0","mstr_symbols","I132";
;
HDL_POWER"P12V_STBY"
BODY_TYPE"PLUMBING"
CDS_LIB"mstr_symbols"
SIZE"1B"
VOLTAGE"12.0V";
"G\NAC"6;
%"CAP"
"1","(-4350,4550)","0","mstr_discrete","I139";
;
CDS_SEC"1"
VOLTAGE"50V"
PACK_TYPE"0402LF"
MATERIAL"COG"
TOLERANCE"5%"
LOCATION"C9G15"
PART_NUMBER"A36095-025"
VALUE"47.0PF"
ROOM"BMC_VOLT_MONITOR"
CDS_LOCATION"C9G15"
SEC"1"
BOM_COST"SM_HM"
CDS_LIB"mstr_discrete"
SEC_TYPE"0402LF";
"A"
$PN"1"21;
"B"
$PN"2"7;
%"RES"
"2","(-4700,4950)","0","mstr_discrete","I141";
;
CDS_SEC"1"
PACK_TYPE"0402"
TOLERANCE"1%"
VALUE"5.11K"
WATTAGE"1/16W"
MATERIAL"CHIP"
PART_NUMBER"G21796-140"
LOCATION"R1U29"
ROOM"BMC_VOLT_MONITOR"
CDS_LOCATION"R1U29"
SEC"1"
SEC_TYPE"0402"
CDS_LIB"mstr_discrete"
BOM_COST"SM_HM";
"A"
$PN"1"8;
"B"
$PN"2"21;
%"GND"
"1","(-4700,4300)","0","mstr_symbols","I143";
;
HDL_POWER"GND"
BODY_TYPE"PLUMBING"
CDS_LIB"mstr_symbols"
SIZE"1B"
VOLTAGE"0";
"A\NAC"7;
%"P5V"
"1","(-4700,5175)","0","mstr_symbols","I144";
;
HDL_POWER"P5V"
BODY_TYPE"PLUMBING"
CDS_LIB"mstr_symbols"
SIZE"1B"
VOLTAGE"5.0V";
"G\NAC"8;
%"CAP"
"1","(-2550,4600)","0","mstr_discrete","I146";
;
CDS_SEC"1"
PART_NUMBER"A36095-025"
LOCATION"C9G14"
VALUE"47.0PF"
MATERIAL"COG"
TOLERANCE"5%"
VOLTAGE"50V"
PACK_TYPE"0402LF"
ROOM"BMC_VOLT_MONITOR"
CDS_LOCATION"C9G14"
SEC"1"
BOM_COST"SM_HM"
CDS_LIB"mstr_discrete"
SEC_TYPE"0402LF";
"A"
$PN"1"26;
"B"
$PN"2"9;
%"RES"
"2","(-2900,5000)","0","mstr_discrete","I148";
;
CDS_SEC"1"
WATTAGE"1/16W"
PART_NUMBER"G21796-140"
MATERIAL"CHIP"
PACK_TYPE"0402"
LOCATION"R1U26"
VALUE"5.11K"
TOLERANCE"1%"
ROOM"BMC_VOLT_MONITOR"
CDS_LOCATION"R1U26"
SEC"1"
SEC_TYPE"0402"
CDS_LIB"mstr_discrete"
BOM_COST"SM_HM";
"A"
$PN"1"10;
"B"
$PN"2"26;
%"GND"
"1","(-2900,4350)","0","mstr_symbols","I150";
;
HDL_POWER"GND"
BODY_TYPE"PLUMBING"
CDS_LIB"mstr_symbols"
SIZE"1B"
VOLTAGE"0";
"A\NAC"9;
%"P3V3"
"1","(-2900,5200)","0","mstr_symbols","I151";
;
HDL_POWER"P3V3"
BODY_TYPE"PLUMBING"
CDS_LIB"mstr_symbols"
SIZE"1B"
VOLTAGE"3.3V";
"G\NAC"10;
%"CAP"
"1","(800,1475)","0","mstr_discrete","I153";
;
CDS_SEC"1"
PART_NUMBER"A36095-025"
MATERIAL"COG"
VALUE"47.0PF"
VOLTAGE"50V"
PACK_TYPE"0402LF"
TOLERANCE"5%"
LOCATION"C9G18"
ROOM"BMC_VOLT_MONITOR"
CDS_LOCATION"C9G18"
SEC"1"
BOM_COST"SM_HM"
CDS_LIB"mstr_discrete"
SEC_TYPE"0402LF";
"A"
$PN"1"27;
"B"
$PN"2"12;
%"PVNN_PCH_STBY"
"1","(800,2025)","0","mstr_symbols","I154";
;
HDL_POWER"PVNN_PCH_STBY"
BODY_TYPE"PLUMBING"
CDS_LIB"mstr_symbols"
VOLTAGE"1.0V";
"G\NAC"11;
%"FERRITE"
"4","(800,1850)","0","mstr_discrete","I155";
;
CDS_SEC"1"
MATERIAL"FB"
LOCATION"FB1U4"
PART_NUMBER"693286-021"
PACK_TYPE"SMLF"
VALUE"30"
ROOM"BMC_VOLT_MONITOR"
CDS_LOCATION"FB1U4"
SEC"1"
BOM_COST"SM_HM"
SEC_TYPE"SMLF"
CDS_LIB"mstr_discrete";
"A"
$PN"1"27;
"B"
$PN"2"11;
%"GND"
"1","(800,1250)","0","mstr_symbols","I156";
;
HDL_POWER"GND"
BODY_TYPE"PLUMBING"
SIZE"1B"
CDS_LIB"mstr_symbols"
VOLTAGE"0";
"A\NAC"12;
%"FET_N_DUAL"
"5","(200,3225)","0","mstr_discrete","I157";
;
CDS_SEC"2"
VALUE"NTJD4001N"
MATERIAL"FET"
LOCATION"Q9G1"
PART_NUMBER"E40049-001"
ROOM"BMC_VOLT_MONITOR"
CDS_LOCATION"Q9G1"
SEC"2"
CDS_LIB"mstr_discrete"
BOM_COST"SM_HM"
SEC_TYPE"SMLF"
PACK_TYPE"SMLF";
"GATE <SIZE -1..0>"
$PN"5"28;
"SOURCE <SIZE-1..0>"
$PN"4"20;
"DRAIN <SIZE -1..0>"
$PN"3"29;
%"GND"
"1","(-875,2525)","0","mstr_symbols","I160";
;
HDL_POWER"GND"
BODY_TYPE"PLUMBING"
CDS_LIB"mstr_symbols"
SIZE"1B"
VOLTAGE"0";
"A\NAC"13;
%"FET_N_DUAL"
"5","(-875,2900)","0","mstr_discrete","I162";
;
CDS_SEC"1"
VALUE"NTJD4001N"
MATERIAL"FET"
PART_NUMBER"E40049-001"
LOCATION"Q9G1"
ROOM"BMC_VOLT_MONITOR"
CDS_LOCATION"Q9G1"
SEC"1"
SEC_TYPE"SMLF"
BOM_COST"SM_HM"
CDS_LIB"mstr_discrete"
PACK_TYPE"SMLF";
"GATE <SIZE -1..0>"
$PN"2"30;
"SOURCE <SIZE-1..0>"
$PN"1"13;
"DRAIN <SIZE -1..0>"
$PN"6"28;
%"RES"
"2","(-650,3375)","0","mstr_discrete","I163";
;
CDS_SEC"1"
LOCATION"R1U49"
WATTAGE"1/16W"
MATERIAL"CHIP"
PACK_TYPE"0402"
TOLERANCE"1%"
VALUE"2.7K"
PART_NUMBER"G21796-344"
ROOM"BMC_VOLT_MONITOR"
CDS_LOCATION"R1U49"
SEC"1"
CDS_LIB"mstr_discrete"
BOM_COST"SM_HM"
SEC_TYPE"0402";
"A"
$PN"1"15;
"B"
$PN"2"28;
%"RES"
"2","(-1400,3025)","0","mstr_discrete","I164";
;
CDS_SEC"1"
CDS_LOCATION"R9G35"
PART_NUMBER"G21796-344"
TOLERANCE"1%"
MATERIAL"CHIP"
WATTAGE"1/16W"
VALUE"2.7K"
LOCATION"R9G35"
PACK_TYPE"0402"
CDS_LIB"mstr_discrete"
SEC_TYPE"0402"
SEC"1";
"A"
$PN"1"14;
"B"
$PN"2"30;
%"P3V3_STBY"
"1","(-1400,3325)","0","mstr_symbols","I165";
;
HDL_POWER"P3V3_STBY"
BODY_TYPE"PLUMBING"
CDS_LIB"mstr_symbols"
SIZE"1B"
VOLTAGE"3.3V";
"G\NAC"14;
%"P3V3_STBY"
"1","(-650,3600)","0","mstr_symbols","I166";
;
HDL_POWER"P3V3_STBY"
BODY_TYPE"PLUMBING"
CDS_LIB"mstr_symbols"
SIZE"1B"
VOLTAGE"3.3V";
"G\NAC"15;
%"1K82R2F-1-GP"
"1","(-4700,4575)","0","w_hdl","I169";
;
CDS_SEC"1"
CDS_LOCATION"R1U28"
ATTRIBUTE"1.82KOHM"
TOLERANCE"1%"
RATED"1/16W"
VALUE"1K82R2F-1-GP"
LOCATION"R1U28"
PACK_SIZE"0402"
SEC_TYPE"SMD-RG"
SEC"1"
PACK_TYPE"SMD-RG"
CDS_LMAN_SYM_OUTLINE"-50,75,50,-75"
CDS_LIB"w_hdl"
PART_NUMBER"64.18215.6DL";
"2"
$PN"2"7;
"1"
$PN"1"21;
%"1K82R2F-1-GP"
"1","(-2850,1375)","0","w_hdl","I170";
;
CDS_SEC"1"
CDS_LOCATION"R1U44"
ATTRIBUTE"1.82KOHM"
RATED"1/16W"
TOLERANCE"1%"
VALUE"1K82R2F-1-GP"
LOCATION"R1U44"
PACK_SIZE"0402"
SEC_TYPE"SMD-RG"
SEC"1"
PACK_TYPE"SMD-RG"
CDS_LMAN_SYM_OUTLINE"-50,75,50,-75"
CDS_LIB"w_hdl"
PART_NUMBER"64.18215.6DL";
"2"
$PN"2"17;
"1"
$PN"1"22;
%"649R2F-GP"
"1","(-1125,1425)","0","w_hdl","I171";
;
CDS_SEC"1"
CDS_LOCATION"R1U33"
ATTRIBUTE"649OHM"
TOLERANCE"1%"
RATED"1/16W"
VALUE"649R2F-GP"
LOCATION"R1U33"
PACK_SIZE"0402"
CDS_LMAN_SYM_OUTLINE"-50,75,50,-75"
CDS_LIB"w_hdl"
PART_NUMBER"64.64905.6DL"
SEC_TYPE"RCL_GP"
SEC"1"
PACK_TYPE"RCL_GP";
"2"
$PN"2"18;
"1"
$PN"1"25;
%"RES"
"1","(-4825,1400)","5","mstr_discrete","I172";
;
CDS_SEC"1"
CDS_LOCATION"R1U38"
PACK_TYPE"0402"
TOLERANCE"1.0%"
LOCATION"R1U38"
VALUE"3.48K"
WATTAGE"1/16W"
MATERIAL"CHIP"
PART_NUMBER"G21796-279"
SEC"1"
SEC_TYPE"0402"
CDS_LIB"mstr_discrete";
"B"
$PN"2"19;
"A"
$PN"1"23;
%"RES"
"1","(-2900,4625)","5","mstr_discrete","I173";
;
CDS_SEC"1"
CDS_LOCATION"R1U27"
TOLERANCE"1.0%"
VALUE"3.48K"
PART_NUMBER"G21796-279"
LOCATION"R1U27"
PACK_TYPE"0402"
MATERIAL"CHIP"
WATTAGE"1/16W"
SEC"1"
SEC_TYPE"0402"
CDS_LIB"mstr_discrete";
"B"
$PN"2"9;
"A"
$PN"1"26;
%"CAP"
"1","(-4825,3250)","0","mstr_discrete","I56";
;
CDS_SEC"1"
PACK_TYPE"0402LF"
PART_NUMBER"A36095-025"
VALUE"47.0PF"
LOCATION"C1U21"
MATERIAL"COG"
VOLTAGE"50V"
TOLERANCE"5%"
ROOM"BMC_VOLT_MONITOR"
CDS_LOCATION"C1U21"
SEC"1"
BOM_COST"SM_HM"
CDS_LIB"mstr_discrete"
SEC_TYPE"0402LF";
"A"
$PN"1"24;
"B"
$PN"2"16;
%"FERRITE"
"4","(-4825,3600)","0","mstr_discrete","I57";
;
CDS_SEC"1"
MATERIAL"FB"
LOCATION"FB1U3"
VALUE"30"
PACK_TYPE"SMLF"
PART_NUMBER"693286-021"
ROOM"BMC_VOLT_MONITOR"
CDS_LOCATION"FB1U3"
SEC"1"
CDS_LIB"mstr_discrete"
SEC_TYPE"SMLF"
BOM_COST"SM_HM";
"A"
$PN"1"24;
"B"
$PN"2"4;
%"GND"
"1","(-4825,3000)","0","mstr_symbols","I58";
;
HDL_POWER"GND"
BODY_TYPE"PLUMBING"
CDS_LIB"mstr_symbols"
SIZE"1B"
VOLTAGE"0";
"A\NAC"16;
%"CAP"
"1","(-2500,1350)","0","mstr_discrete","I68";
;
CDS_SEC"1"
MATERIAL"COG"
PART_NUMBER"A36095-025"
PACK_TYPE"0402LF"
LOCATION"C9G21"
VOLTAGE"50V"
TOLERANCE"5%"
VALUE"47.0PF"
ROOM"BMC_VOLT_MONITOR"
CDS_LOCATION"C9G21"
SEC"1"
SEC_TYPE"0402LF"
CDS_LIB"mstr_discrete"
BOM_COST"SM_HM";
"A"
$PN"1"22;
"B"
$PN"2"17;
%"GND"
"1","(-2850,1100)","0","mstr_symbols","I71";
;
HDL_POWER"GND"
BODY_TYPE"PLUMBING"
CDS_LIB"mstr_symbols"
SIZE"1B"
VOLTAGE"0";
"A\NAC"17;
%"CAP"
"1","(-775,1450)","0","mstr_discrete","I80";
;
CDS_SEC"1"
PACK_TYPE"0402LF"
MATERIAL"COG"
PART_NUMBER"A36095-025"
VALUE"47.0PF"
LOCATION"C9G17"
VOLTAGE"50V"
TOLERANCE"5%"
ROOM"BMC_VOLT_MONITOR"
CDS_LOCATION"C9G17"
SEC"1"
SEC_TYPE"0402LF"
CDS_LIB"mstr_discrete"
BOM_COST"SM_HM";
"A"
$PN"1"25;
"B"
$PN"2"18;
%"RES"
"2","(-1125,1825)","0","mstr_discrete","I82";
;
CDS_SEC"1"
WATTAGE"1/16W"
TOLERANCE"1%"
PACK_TYPE"0402"
LOCATION"R1U32"
VALUE"5.11K"
MATERIAL"CHIP"
PART_NUMBER"G21796-140"
ROOM"BMC_VOLT_MONITOR"
CDS_LOCATION"R1U32"
SEC"1"
BOM_COST"SM_HM"
CDS_LIB"mstr_discrete"
SEC_TYPE"0402";
"A"
$PN"1"6;
"B"
$PN"2"25;
%"GND"
"1","(-1125,1175)","0","mstr_symbols","I84";
;
HDL_POWER"GND"
BODY_TYPE"PLUMBING"
CDS_LIB"mstr_symbols"
SIZE"1B"
VOLTAGE"0";
"A\NAC"18;
%"CAP"
"1","(-4475,1425)","0","mstr_discrete","I86";
;
CDS_SEC"1"
VALUE"47.0PF"
VOLTAGE"50V"
TOLERANCE"5%"
MATERIAL"COG"
LOCATION"C9G20"
PART_NUMBER"A36095-025"
PACK_TYPE"0402LF"
BOM_COST"SM_HM"
CDS_LIB"mstr_discrete"
SEC_TYPE"0402LF"
SEC"1"
CDS_LOCATION"C9G20"
ROOM"BMC_VOLT_MONITOR";
"A"
$PN"1"23;
"B"
$PN"2"19;
%"RES"
"2","(-4825,1800)","0","mstr_discrete","I88";
;
CDS_SEC"1"
PACK_TYPE"0402"
MATERIAL"CHIP"
LOCATION"R1U39"
PART_NUMBER"G21796-140"
VALUE"5.11K"
TOLERANCE"1%"
WATTAGE"1/16W"
ROOM"BMC_VOLT_MONITOR"
CDS_LOCATION"R1U39"
SEC"1"
BOM_COST"SM_HM"
CDS_LIB"mstr_discrete"
SEC_TYPE"0402";
"A"
$PN"1"5;
"B"
$PN"2"23;
%"GND"
"1","(-4825,1150)","0","mstr_symbols","I90";
;
HDL_POWER"GND"
BODY_TYPE"PLUMBING"
CDS_LIB"mstr_symbols"
SIZE"1B"
VOLTAGE"0";
"A\NAC"19;
END.
